# T6G (Grand Teton) — schematic netlist excerpt (pin names and nets, part order shuffled) for the footprints in the layout excerpt that follows; sources: Cadence DE-HDL packaged netlist, KiCad conversion of 04192023_DAF0TMB3IC0_F0TG_MB_C_brd_V02_OCP.brd

R3796  Q_RES  100K 1% CHIP  pkg 0402LF  page 134 : A = P3V3_AUX ; B = P3V3_OCP_FAULT_1
R1091  Q_RES  4.7K 5% EMPTY  pkg 0201LF  page 309 : A = MODE_RT_CPU0_P3 ; B = GND
C2283  Q_CAP  22UF 4V 20% X6S  pkg C0402  page 72 : A = PVDDCR_SOC_P1 ; B = GND

(kicad_pcb
	(version 20260206)
	(generator "pcbnew")
	(generator_version "10.0")
	(general
		(thickness 1.6)
		(legacy_teardrops no)
	)
	(paper "A4")
	(title_block
		(title "04192023_DAF0TMB3IC0_F0TG_MB_C_brd_V02_OCP.brd")
		(comment 1 "Grand Teton / footprints 424-426 of 8354")
	)
	(layers
		(0 "F.Cu" signal "TOP")
		(4 "In1.Cu" signal "GND")
		(6 "In2.Cu" signal "IN1")
		(8 "In3.Cu" signal "GND1")
		(10 "In4.Cu" signal "IN2")
		(12 "In5.Cu" signal "GND2")
		(14 "In6.Cu" signal "IN3")
		(16 "In7.Cu" signal "GND3")
		(18 "In8.Cu" signal "VCC")
		(20 "In9.Cu" signal "VCC1")
		(22 "In10.Cu" signal "GND4")
		(24 "In11.Cu" signal "IN4")
		(26 "In12.Cu" signal "GND5")
		(28 "In13.Cu" signal "IN5")
		(30 "In14.Cu" signal "GND6")
		(32 "In15.Cu" signal "IN6")
		(34 "In16.Cu" signal "GND7")
		(2 "B.Cu" signal "BOTTOM")
		(9 "F.Adhes" user "F.Adhesive")
		(11 "B.Adhes" user "B.Adhesive")
		(13 "F.Paste" user "Package Geometry/Pastemask Top")
		(15 "B.Paste" user "Package Geometry/Pastemask Bottom")
		(5 "F.SilkS" user "Ref Des/Silkscreen Top")
		(7 "B.SilkS" user "Ref Des/Silkscreen Bottom")
		(1 "F.Mask" user "Board Geometry/Soldermask Top")
		(3 "B.Mask" user "Board Geometry/Soldermask Bottom")
		(17 "Dwgs.User" user "User.Drawings")
		(19 "Cmts.User" user "User.Comments")
		(21 "Eco1.User" user "User.Eco1")
		(23 "Eco2.User" user "User.Eco2")
		(25 "Edge.Cuts" user "Board Geometry/Outline")
		(27 "Margin" user)
		(31 "F.CrtYd" user "Package Geometry/Place Bound Top")
		(29 "B.CrtYd" user "Package Geometry/Place Bound Bottom")
		(35 "F.Fab" user "Ref Des/Assembly Top")
		(33 "B.Fab" user "Ref Des/Assembly Bottom")
	)
	(footprint ""
		(layer "F.Cu")
		(at 432.151536 -101.97719)
		(property "Reference" "R3796"
			(at 0 0 0)
			(layer "F.SilkS")
			(hide yes)
			(effects
				(font
					(size 1.27 1.27)
				)
			)
		)
		(property "Value" ""
			(at 0 0 0)
			(layer "F.Fab")
			(effects
				(font
					(size 1.27 1.27)
				)
			)
		)
		(duplicate_pad_numbers_are_jumpers no)
		(fp_line
			(start -0.7874 -0.4064)
			(end 0.7874 -0.4064)
			(stroke
				(width 0.1524)
				(type default)
			)
			(layer "F.SilkS")
		)
		(fp_line
			(start -0.7874 0.4064)
			(end -0.7874 -0.4064)
			(stroke
				(width 0.1524)
				(type default)
			)
			(layer "F.SilkS")
		)
		(fp_line
			(start 0.7874 -0.4064)
			(end 0.7874 0.4064)
			(stroke
				(width 0.1524)
				(type default)
			)
			(layer "F.SilkS")
		)
		(fp_line
			(start 0.7874 0.4064)
			(end -0.7874 0.4064)
			(stroke
				(width 0.1524)
				(type default)
			)
			(layer "F.SilkS")
		)
		(fp_line
			(start -0.67945 -0.305054)
			(end -0.12065 -0.305054)
			(stroke
				(width 0.1)
				(type default)
			)
			(layer "F.Fab")
		)
		(fp_line
			(start -0.67945 0.3048)
			(end -0.67945 -0.305054)
			(stroke
				(width 0.1)
				(type default)
			)
			(layer "F.Fab")
		)
		(fp_line
			(start -0.12065 -0.305054)
			(end -0.12065 -0.2794)
			(stroke
				(width 0.1)
				(type default)
			)
			(layer "F.Fab")
		)
		(fp_line
			(start -0.12065 -0.2794)
			(end 0.12065 -0.2794)
			(stroke
				(width 0.1)
				(type default)
			)
			(layer "F.Fab")
		)
		(fp_line
			(start -0.12065 0.2794)
			(end -0.12065 0.3048)
			(stroke
				(width 0.1)
				(type default)
			)
			(layer "F.Fab")
		)
		(fp_line
			(start -0.12065 0.3048)
			(end -0.67945 0.3048)
			(stroke
				(width 0.1)
				(type default)
			)
			(layer "F.Fab")
		)
		(fp_line
			(start 0.120396 0.2794)
			(end -0.12065 0.2794)
			(stroke
				(width 0.1)
				(type default)
			)
			(layer "F.Fab")
		)
		(fp_line
			(start 0.120396 0.3048)
			(end 0.120396 0.2794)
			(stroke
				(width 0.1)
				(type default)
			)
			(layer "F.Fab")
		)
		(fp_line
			(start 0.12065 -0.3048)
			(end 0.67945 -0.3048)
			(stroke
				(width 0.1)
				(type default)
			)
			(layer "F.Fab")
		)
		(fp_line
			(start 0.12065 -0.2794)
			(end 0.12065 -0.3048)
			(stroke
				(width 0.1)
				(type default)
			)
			(layer "F.Fab")
		)
		(fp_line
			(start 0.67945 -0.3048)
			(end 0.67945 0.3048)
			(stroke
				(width 0.1)
				(type default)
			)
			(layer "F.Fab")
		)
		(fp_line
			(start 0.67945 0.3048)
			(end 0.120396 0.3048)
			(stroke
				(width 0.1)
				(type default)
			)
			(layer "F.Fab")
		)
		(pad "1" smd circle
			(at -0.40005 0)
			(size 0 0)
			(layers "F.Cu" "F.Mask" "F.Paste")
			(net "P3V3_AUX")
		)
		(pad "2" smd circle
			(at 0.40005 0)
			(size 0 0)
			(layers "F.Cu" "F.Mask" "F.Paste")
			(net "P3V3_OCP_FAULT_1")
		)
	)
	(footprint ""
		(layer "F.Cu")
		(at 117.895624 -255.555242 180)
		(property "Reference" "C2283"
			(at 0 0 180)
			(layer "F.SilkS")
			(hide yes)
			(effects
				(font
					(size 1.27 1.27)
				)
			)
		)
		(property "Value" ""
			(at 0 0 180)
			(layer "F.Fab")
			(effects
				(font
					(size 1.27 1.27)
				)
			)
		)
		(duplicate_pad_numbers_are_jumpers no)
		(fp_line
			(start 0.7874 0.4064)
			(end -0.7874 0.4064)
			(stroke
				(width 0.1524)
				(type default)
			)
			(layer "F.SilkS")
		)
		(fp_line
			(start 0.7874 -0.4064)
			(end 0.7874 0.4064)
			(stroke
				(width 0.1524)
				(type default)
			)
			(layer "F.SilkS")
		)
		(fp_line
			(start -0.7874 0.4064)
			(end -0.7874 -0.4064)
			(stroke
				(width 0.1524)
				(type default)
			)
			(layer "F.SilkS")
		)
		(fp_line
			(start -0.7874 -0.4064)
			(end 0.7874 -0.4064)
			(stroke
				(width 0.1524)
				(type default)
			)
			(layer "F.SilkS")
		)
		(fp_line
			(start 0.67945 0.3048)
			(end 0.120396 0.3048)
			(stroke
				(width 0.1)
				(type default)
			)
			(layer "F.Fab")
		)
		(fp_line
			(start 0.67945 -0.3048)
			(end 0.67945 0.3048)
			(stroke
				(width 0.1)
				(type default)
			)
			(layer "F.Fab")
		)
		(fp_line
			(start 0.12065 -0.2794)
			(end 0.12065 -0.3048)
			(stroke
				(width 0.1)
				(type default)
			)
			(layer "F.Fab")
		)
		(fp_line
			(start 0.12065 -0.3048)
			(end 0.67945 -0.3048)
			(stroke
				(width 0.1)
				(type default)
			)
			(layer "F.Fab")
		)
		(fp_line
			(start 0.120396 0.3048)
			(end 0.120396 0.2794)
			(stroke
				(width 0.1)
				(type default)
			)
			(layer "F.Fab")
		)
		(fp_line
			(start 0.120396 0.2794)
			(end -0.12065 0.2794)
			(stroke
				(width 0.1)
				(type default)
			)
			(layer "F.Fab")
		)
		(fp_line
			(start -0.12065 0.3048)
			(end -0.67945 0.3048)
			(stroke
				(width 0.1)
				(type default)
			)
			(layer "F.Fab")
		)
		(fp_line
			(start -0.12065 0.2794)
			(end -0.12065 0.3048)
			(stroke
				(width 0.1)
				(type default)
			)
			(layer "F.Fab")
		)
		(fp_line
			(start -0.12065 -0.2794)
			(end 0.12065 -0.2794)
			(stroke
				(width 0.1)
				(type default)
			)
			(layer "F.Fab")
		)
		(fp_line
			(start -0.12065 -0.305054)
			(end -0.12065 -0.2794)
			(stroke
				(width 0.1)
				(type default)
			)
			(layer "F.Fab")
		)
		(fp_line
			(start -0.67945 0.3048)
			(end -0.67945 -0.305054)
			(stroke
				(width 0.1)
				(type default)
			)
			(layer "F.Fab")
		)
		(fp_line
			(start -0.67945 -0.305054)
			(end -0.12065 -0.305054)
			(stroke
				(width 0.1)
				(type default)
			)
			(layer "F.Fab")
		)
		(pad "1" smd circle
			(at -0.40005 0 180)
			(size 0 0)
			(layers "F.Cu" "F.Mask" "F.Paste")
			(net "PVDDCR_SOC_P1")
		)
		(pad "2" smd circle
			(at 0.40005 0 180)
			(size 0 0)
			(layers "F.Cu" "F.Mask" "F.Paste")
			(net "GND")
		)
	)
	(footprint ""
		(layer "F.Cu")
		(at 368.600736 -402.548852 -90)
		(property "Reference" "R1091"
			(at 0 0 270)
			(layer "F.SilkS")
			(hide yes)
			(effects
				(font
					(size 1.27 1.27)
				)
			)
		)
		(property "Value" ""
			(at 0 0 270)
			(layer "F.Fab")
			(effects
				(font
					(size 1.27 1.27)
				)
			)
		)
		(duplicate_pad_numbers_are_jumpers no)
		(fp_line
			(start -0.32512 0.175006)
			(end -0.32512 -0.175006)
			(stroke
				(width 0.1)
				(type default)
			)
			(layer "F.Fab")
		)
		(fp_line
			(start 0.32512 0.175006)
			(end -0.32512 0.175006)
			(stroke
				(width 0.1)
				(type default)
			)
			(layer "F.Fab")
		)
		(fp_line
			(start -0.32512 -0.175006)
			(end 0.32512 -0.175006)
			(stroke
				(width 0.1)
				(type default)
			)
			(layer "F.Fab")
		)
		(fp_line
			(start 0.32512 -0.175006)
			(end 0.32512 0.175006)
			(stroke
				(width 0.1)
				(type default)
			)
			(layer "F.Fab")
		)
		(pad "1" smd rect
			(at -0.2667 0 270)
			(size 0.3048 0.381)
			(layers "F.Cu" "F.Mask" "F.Paste")
			(net "MODE_RT_CPU0_P3")
		)
		(pad "2" smd rect
			(at 0.2667 0 90)
			(size 0.3048 0.381)
			(layers "F.Cu" "F.Mask" "F.Paste")
			(net "GND")
		)
	)
)
